(kicad_pcb
	(version 20260206)
	(generator "pcbnew")
	(generator_version "10.0")
	(general
		(thickness 1.6)
		(legacy_teardrops no)
	)
	(paper "A4")
	(title_block
		(title "03242023_DA0F0TMBIJ0_F0T_Motherboard_J_brd_V01_OCP.brd")
		(comment 1 "Grand Teton / footprints 3157-3159 of 6105")
	)
	(layers
		(0 "F.Cu" signal "TOP")
		(4 "In1.Cu" signal "GND")
		(6 "In2.Cu" signal "IN1")
		(8 "In3.Cu" signal "GND1")
		(10 "In4.Cu" signal "IN2")
		(12 "In5.Cu" signal "GND2")
		(14 "In6.Cu" signal "IN3")
		(16 "In7.Cu" signal "GND3")
		(18 "In8.Cu" signal "VCC")
		(20 "In9.Cu" signal "VCC1")
		(22 "In10.Cu" signal "GND4")
		(24 "In11.Cu" signal "IN4")
		(26 "In12.Cu" signal "GND5")
		(28 "In13.Cu" signal "IN5")
		(30 "In14.Cu" signal "GND6")
		(32 "In15.Cu" signal "IN6")
		(34 "In16.Cu" signal "GND7")
		(2 "B.Cu" signal "BOTTOM")
		(9 "F.Adhes" user "F.Adhesive")
		(11 "B.Adhes" user "B.Adhesive")
		(13 "F.Paste" user "Package Geometry/Pastemask Top")
		(15 "B.Paste" user "Package Geometry/Pastemask Bottom")
		(5 "F.SilkS" user "Ref Des/Silkscreen Top")
		(7 "B.SilkS" user "Ref Des/Silkscreen Bottom")
		(1 "F.Mask" user "Board Geometry/Soldermask Top")
		(3 "B.Mask" user "Board Geometry/Soldermask Bottom")
		(17 "Dwgs.User" user "User.Drawings")
		(19 "Cmts.User" user "User.Comments")
		(21 "Eco1.User" user "User.Eco1")
		(23 "Eco2.User" user "User.Eco2")
		(25 "Edge.Cuts" user "Board Geometry/Outline")
		(27 "Margin" user)
		(31 "F.CrtYd" user "Package Geometry/Place Bound Top")
		(29 "B.CrtYd" user "Package Geometry/Place Bound Bottom")
		(35 "F.Fab" user "Ref Des/Assembly Top")
		(33 "B.Fab" user "Ref Des/Assembly Bottom")
	)
	(footprint ""
		(layer "F.Cu")
		(at 53.190902 -174.230792 90)
		(property "Reference" "PU49"
			(at 1.292606 -8.370062 0)
			(unlocked yes)
			(layer "F.SilkS")
			(effects
				(font
					(size 0.7874 0.5842)
					(thickness 0.1524)
				)
				(justify left)
			)
		)
		(property "Value" ""
			(at 0 0 90)
			(layer "F.Fab")
			(effects
				(font
					(size 1.27 1.27)
				)
			)
		)
		(duplicate_pad_numbers_are_jumpers no)
		(fp_line
			(start 2.050034 -2.549906)
			(end 1.916684 -2.549906)
			(stroke
				(width 0.1524)
				(type default)
			)
			(layer "F.SilkS")
		)
		(fp_line
			(start -1.61671 -2.549906)
			(end -2.050034 -2.549906)
			(stroke
				(width 0.1524)
				(type default)
			)
			(layer "F.SilkS")
		)
		(fp_line
			(start -2.050034 -2.549906)
			(end -2.050034 -2.126742)
			(stroke
				(width 0.1524)
				(type default)
			)
			(layer "F.SilkS")
		)
		(fp_line
			(start 2.050034 -1.981708)
			(end 2.050034 -2.549906)
			(stroke
				(width 0.1524)
				(type default)
			)
			(layer "F.SilkS")
		)
		(fp_line
			(start 2.050034 0.08636)
			(end 2.050034 -0.178308)
			(stroke
				(width 0.1524)
				(type default)
			)
			(layer "F.SilkS")
		)
		(fp_line
			(start -2.050034 0.406654)
			(end -2.050034 0.786384)
			(stroke
				(width 0.1524)
				(type default)
			)
			(layer "F.SilkS")
		)
		(fp_line
			(start -2.050034 1.88976)
			(end -2.050034 2.549906)
			(stroke
				(width 0.1524)
				(type default)
			)
			(layer "F.SilkS")
		)
		(fp_line
			(start 2.050034 2.549906)
			(end 2.050034 1.88976)
			(stroke
				(width 0.1524)
				(type default)
			)
			(layer "F.SilkS")
		)
		(fp_line
			(start 1.27 2.549906)
			(end 2.050034 2.549906)
			(stroke
				(width 0.1524)
				(type default)
			)
			(layer "F.SilkS")
		)
		(fp_line
			(start -2.050034 2.549906)
			(end -1.27 2.549906)
			(stroke
				(width 0.1524)
				(type default)
			)
			(layer "F.SilkS")
		)
		(fp_poly
			(pts
				(xy -2.33553 -1.898142) (xy -2.711704 -1.710182) (xy -2.711704 -2.086102)
			)
			(stroke
				(width 0)
				(type default)
			)
			(fill yes)
			(layer "F.SilkS")
		)
		(fp_line
			(start 2.050034 -2.549906)
			(end -2.050034 -2.549906)
			(stroke
				(width 0.1)
				(type default)
			)
			(layer "F.Fab")
		)
		(fp_line
			(start -2.050034 -2.549906)
			(end -2.050034 2.549906)
			(stroke
				(width 0.1)
				(type default)
			)
			(layer "F.Fab")
		)
		(fp_line
			(start 2.050034 2.549906)
			(end 2.050034 -2.549906)
			(stroke
				(width 0.1)
				(type default)
			)
			(layer "F.Fab")
		)
		(fp_line
			(start -2.050034 2.549906)
			(end 2.050034 2.549906)
			(stroke
				(width 0.1)
				(type default)
			)
			(layer "F.Fab")
		)
		(fp_poly
			(pts
				(xy -3.43789 -2.368042) (xy -3.43789 -1.352042) (xy -2.42189 -1.860042)
			)
			(stroke
				(width 0)
				(type default)
			)
			(fill yes)
			(layer "F.Fab")
		)
		(pad "1" smd rect
			(at -1.925066 -1.860042)
			(size 0.254 0.5588)
			(layers "F.Cu" "F.Mask" "F.Paste")
			(net "PVCCFA_EHV_CPU1_BTSEN")
		)
		(pad "2" smd rect
			(at -1.925066 -1.359916)
			(size 0.254 0.5588)
			(layers "F.Cu" "F.Mask" "F.Paste")
			(net "PVCCFA_EHV_CPU1_FAULT")
		)
		(pad "3" smd rect
			(at -1.925066 -0.860044)
			(size 0.254 0.5588)
			(layers "F.Cu" "F.Mask" "F.Paste")
			(net "PVCCFA_EHV_CPU1_NC1")
		)
		(pad "4" smd rect
			(at -1.925066 -0.359918)
			(size 0.254 0.5588)
			(layers "F.Cu" "F.Mask" "F.Paste")
			(net "PVCCFA_EHV_CPU1_VDD1")
		)
		(pad "5" smd rect
			(at -1.925066 0.139954)
			(size 0.254 0.5588)
			(layers "F.Cu" "F.Mask" "F.Paste")
			(net "PVCCFA_EHV_CPU1_LSET1")
		)
		(pad "6_7-13_15-29" smd circle
			(at 0 0.98806 180)
			(size 0 0)
			(layers "F.Cu" "F.Mask" "F.Paste")
			(net "GND")
		)
		(pad "8_12" smd rect
			(at 0 2.400046)
			(size 0.6096 2.2606)
			(layers "F.Cu" "F.Mask" "F.Paste")
			(net "SW_PVCCFA_EHV_CPU1_SW1")
		)
		(pad "16_18-28" smd rect
			(at 1.480566 -1.080008 90)
			(size 1.4478 1.524)
			(layers "F.Cu" "F.Mask" "F.Paste")
			(net "SW_P12V_PVCCINFAON_CPU1_FLT")
		)
		(pad "19" smd rect
			(at 1.649984 -2.424938 90)
			(size 0.254 0.5588)
			(layers "F.Cu" "F.Mask" "F.Paste")
			(net "SW_PVCCFA_EHV_CPU1_BOOTR1")
		)
		(pad "20" smd rect
			(at 1.150112 -2.424938 90)
			(size 0.254 0.5588)
			(layers "F.Cu" "F.Mask" "F.Paste")
			(net "SW_PVCCFA_EHV_CPU1_BOOT1")
		)
		(pad "21" smd rect
			(at 0.649986 -2.424938 90)
			(size 0.254 0.5588)
			(layers "F.Cu" "F.Mask" "F.Paste")
			(net "PVCCFA_EHV_CPU1_BPWM1")
		)
		(pad "22" smd rect
			(at 0.150114 -2.424938 90)
			(size 0.254 0.5588)
			(layers "F.Cu" "F.Mask" "F.Paste")
			(net "PVCCFA_EHV_CPU1_NC2")
		)
		(pad "23" smd rect
			(at -0.350012 -2.424938 90)
			(size 0.254 0.5588)
			(layers "F.Cu" "F.Mask" "F.Paste")
			(net "GND")
		)
		(pad "24" smd rect
			(at -0.849884 -2.424938 90)
			(size 0.254 0.5588)
			(layers "F.Cu" "F.Mask" "F.Paste")
			(net "PVCCINFAON_CPU1_VREF")
		)
		(pad "25" smd rect
			(at -1.35001 -2.424938 90)
			(size 0.254 0.5588)
			(layers "F.Cu" "F.Mask" "F.Paste")
			(net "PVCCFA_EHV_CPU1_BCSP1")
		)
		(pad "26" smd circle
			(at -0.490728 -1.009396 180)
			(size 0 0)
			(layers "F.Cu" "F.Mask" "F.Paste")
			(net "GND")
		)
		(pad "27" smd rect
			(at -1.124966 0.425958)
			(size 0.2032 0.3556)
			(layers "F.Cu" "F.Mask" "F.Paste")
			(net "Net_8493")
		)
		(zone
			(layer "F.Cu")
			(hatch none 0.5)
			(connect_pads
				(clearance 0)
			)
			(min_thickness 0.25)
			(keepout
				(tracks not_allowed)
				(vias allowed)
				(pads allowed)
				(copperpour not_allowed)
				(footprints allowed)
			)
			(placement
				(enabled no)
				(sheetname "")
			)
			(fill
				(thermal_gap 0.5)
				(thermal_bridge_width 0.5)
				(island_removal_mode 0)
			)
			(polygon
				(pts
					(xy 54.991762 -172.43552) (xy 54.991762 -175.979328) (xy 55.235348 -176.222914) (xy 55.235348 -172.191934)
				)
			)
		)
		(zone
			(layer "F.Cu")
			(hatch none 0.5)
			(connect_pads
				(clearance 0)
			)
			(min_thickness 0.25)
			(keepout
				(tracks not_allowed)
				(vias allowed)
				(pads allowed)
				(copperpour not_allowed)
				(footprints allowed)
			)
			(placement
				(enabled no)
				(sheetname "")
			)
			(fill
				(thermal_gap 0.5)
				(thermal_bridge_width 0.5)
				(island_removal_mode 0)
			)
			(polygon
				(pts
					(xy 53.3781 -173.734984) (xy 54.066186 -173.734984) (xy 54.066186 -172.180758) (xy 53.622702 -172.180758)
					(xy 53.622702 -172.877226) (xy 53.76926 -172.877226) (xy 53.76926 -173.334426) (xy 53.46446 -173.334426)
					(xy 53.46446 -172.877226) (xy 53.597302 -172.877226) (xy 53.597302 -172.180758) (xy 53.508656 -172.180758)
					(xy 53.508656 -172.635926) (xy 51.590702 -172.635926) (xy 51.590702 -172.812456) (xy 53.090318 -172.812456)
					(xy 53.090318 -173.561248) (xy 53.3781 -173.561248)
				)
			)
		)
	)
	(footprint ""
		(layer "F.Cu")
		(at 268.645132 -51.999896)
		(property "Reference" "H111"
			(at -9.58596 -6.67131 0)
			(unlocked yes)
			(layer "F.SilkS")
			(effects
				(font
					(size 0.7874 0.5842)
					(thickness 0.1524)
				)
				(justify left)
			)
		)
		(property "Value" ""
			(at 0 0 0)
			(layer "F.Fab")
			(effects
				(font
					(size 1.27 1.27)
				)
			)
		)
		(duplicate_pad_numbers_are_jumpers no)
		(fp_circle
			(center 0 0)
			(end 7.999984 0)
			(stroke
				(width 0.1524)
				(type default)
			)
			(fill no)
			(layer "F.SilkS")
		)
		(fp_circle
			(center 0 0)
			(end 7.999984 0)
			(stroke
				(width 0.1524)
				(type default)
			)
			(fill no)
			(layer "B.SilkS")
		)
		(fp_circle
			(center 0 0)
			(end 7.999984 0)
			(stroke
				(width 0.1)
				(type default)
			)
			(fill no)
			(layer "B.Fab")
		)
		(fp_circle
			(center 0 0)
			(end 7.999984 0)
			(stroke
				(width 0.1)
				(type default)
			)
			(fill no)
			(layer "F.Fab")
		)
		(pad "" np_thru_hole circle
			(at 0 0)
			(size 5.5118 5.5118)
			(drill 5.5118)
			(layers "*.Cu" "*.Mask")
			(clearance 0.381)
			(thermal_gap 0.381)
		)
		(pad "2" thru_hole circle
			(at 0 -3.999992)
			(size 0.762 0.762)
			(drill 0.5588)
			(layers "*.Cu" "*.Mask")
			(remove_unused_layers no)
			(net "GND")
			(clearance 0.1524)
			(thermal_gap 0.1524)
		)
		(pad "3" thru_hole circle
			(at -2.999994 -2.500122)
			(size 0.762 0.762)
			(drill 0.5588)
			(layers "*.Cu" "*.Mask")
			(remove_unused_layers no)
			(net "GND")
			(clearance 0.1524)
			(thermal_gap 0.1524)
		)
		(pad "4" thru_hole circle
			(at -3.999992 0)
			(size 0.762 0.762)
			(drill 0.5588)
			(layers "*.Cu" "*.Mask")
			(remove_unused_layers no)
			(net "GND")
			(clearance 0.1524)
			(thermal_gap 0.1524)
		)
		(pad "5" thru_hole circle
			(at -2.999994 2.500122)
			(size 0.762 0.762)
			(drill 0.5588)
			(layers "*.Cu" "*.Mask")
			(remove_unused_layers no)
			(net "GND")
			(clearance 0.1524)
			(thermal_gap 0.1524)
		)
		(pad "6" thru_hole circle
			(at 0 3.999992)
			(size 0.762 0.762)
			(drill 0.5588)
			(layers "*.Cu" "*.Mask")
			(remove_unused_layers no)
			(net "GND")
			(clearance 0.1524)
			(thermal_gap 0.1524)
		)
		(pad "7" thru_hole circle
			(at 2.999994 2.500122)
			(size 0.762 0.762)
			(drill 0.5588)
			(layers "*.Cu" "*.Mask")
			(remove_unused_layers no)
			(net "GND")
			(clearance 0.1524)
			(thermal_gap 0.1524)
		)
		(pad "8" thru_hole circle
			(at 3.999992 0)
			(size 0.762 0.762)
			(drill 0.5588)
			(layers "*.Cu" "*.Mask")
			(remove_unused_layers no)
			(net "GND")
			(clearance 0.1524)
			(thermal_gap 0.1524)
		)
		(pad "9" thru_hole circle
			(at 2.999994 -2.500122)
			(size 0.762 0.762)
			(drill 0.5588)
			(layers "*.Cu" "*.Mask")
			(remove_unused_layers no)
			(net "GND")
			(clearance 0.1524)
			(thermal_gap 0.1524)
		)
		(zone
			(layer "F.Cu")
			(hatch none 0.5)
			(connect_pads
				(clearance 0)
			)
			(min_thickness 0.25)
			(keepout
				(tracks not_allowed)
				(vias allowed)
				(pads allowed)
				(copperpour not_allowed)
				(footprints allowed)
			)
			(placement
				(enabled no)
				(sheetname "")
			)
			(fill
				(thermal_gap 0.5)
				(thermal_bridge_width 0.5)
				(island_removal_mode 0)
			)
			(polygon
				(pts
					(arc
						(start 268.645132 -59.99988)
						(mid 262.988289 -57.656739)
						(end 260.645148 -51.999896)
					)
					(arc
						(start 260.645148 -51.999896)
						(mid 262.988289 -46.343053)
						(end 268.645132 -43.999912)
					)
					(xy 268.645132 -46.74616) (xy 268.594078 -46.74616)
					(arc
						(start 268.593824 -46.74616)
						(mid 263.391145 -51.999896)
						(end 268.593824 -57.253632)
					)
					(xy 268.594078 -57.253632) (xy 268.645132 -57.253632)
				)
			)
		)
		(zone
			(layer "F.Cu")
			(hatch none 0.5)
			(connect_pads
				(clearance 0)
			)
			(min_thickness 0.25)
			(keepout
				(tracks not_allowed)
				(vias allowed)
				(pads allowed)
				(copperpour not_allowed)
				(footprints allowed)
			)
			(placement
				(enabled no)
				(sheetname "")
			)
			(fill
				(thermal_gap 0.5)
				(thermal_bridge_width 0.5)
				(island_removal_mode 0)
			)
			(polygon
				(pts
					(arc
						(start 268.645132 -59.99988)
						(mid 274.301975 -57.656739)
						(end 276.645116 -51.999896)
					)
					(arc
						(start 276.645116 -51.999896)
						(mid 274.301975 -46.343053)
						(end 268.645132 -43.999912)
					)
					(xy 268.645132 -46.74616) (xy 268.696186 -46.74616)
					(arc
						(start 268.69644 -46.74616)
						(mid 273.899119 -51.999896)
						(end 268.69644 -57.253632)
					)
					(xy 268.696186 -57.253632) (xy 268.645132 -57.253632)
				)
			)
		)
		(zone
			(layers "F.Cu" "B.Cu" "In1.Cu" "In2.Cu" "In3.Cu" "In4.Cu" "In5.Cu" "In6.Cu"
				"In7.Cu" "In8.Cu" "In9.Cu" "In10.Cu" "In11.Cu" "In12.Cu" "In13.Cu" "In14.Cu"
				"In15.Cu" "In16.Cu"
			)
			(hatch none 0.5)
			(connect_pads
				(clearance 0)
			)
			(min_thickness 0.25)
			(keepout
				(tracks not_allowed)
				(vias allowed)
				(pads allowed)
				(copperpour not_allowed)
				(footprints allowed)
			)
			(placement
				(enabled no)
				(sheetname "")
			)
			(fill
				(thermal_gap 0.5)
				(thermal_bridge_width 0.5)
				(island_removal_mode 0)
			)
			(polygon
				(pts
					(arc
						(start 271.921732 -51.999896)
						(mid 265.368532 -51.999896)
						(end 271.921732 -51.999896)
					)
				)
			)
		)
		(zone
			(layer "B.Cu")
			(hatch none 0.5)
			(connect_pads
				(clearance 0)
			)
			(min_thickness 0.25)
			(keepout
				(tracks not_allowed)
				(vias allowed)
				(pads allowed)
				(copperpour not_allowed)
				(footprints allowed)
			)
			(placement
				(enabled no)
				(sheetname "")
			)
			(fill
				(thermal_gap 0.5)
				(thermal_bridge_width 0.5)
				(island_removal_mode 0)
			)
			(polygon
				(pts
					(arc
						(start 268.645132 -57.507886)
						(mid 263.137142 -51.999896)
						(end 268.645132 -46.491906)
					)
					(arc
						(start 268.645132 -46.974506)
						(mid 263.619742 -51.999896)
						(end 268.645132 -57.025286)
					)
				)
			)
		)
		(zone
			(layer "B.Cu")
			(hatch none 0.5)
			(connect_pads
				(clearance 0)
			)
			(min_thickness 0.25)
			(keepout
				(tracks not_allowed)
				(vias allowed)
				(pads allowed)
				(copperpour not_allowed)
				(footprints allowed)
			)
			(placement
				(enabled no)
				(sheetname "")
			)
			(fill
				(thermal_gap 0.5)
				(thermal_bridge_width 0.5)
				(island_removal_mode 0)
			)
			(polygon
				(pts
					(arc
						(start 268.645132 -57.507886)
						(mid 274.153122 -51.999896)
						(end 268.645132 -46.491906)
					)
					(arc
						(start 268.645132 -46.974506)
						(mid 273.670522 -51.999896)
						(end 268.645132 -57.025286)
					)
				)
			)
		)
	)
	(footprint ""
		(layer "F.Cu")
		(at 449.973954 -119.429022 180)
		(property "Reference" "R1921"
			(at 0 0 180)
			(layer "F.SilkS")
			(hide yes)
			(effects
				(font
					(size 1.27 1.27)
				)
			)
		)
		(property "Value" ""
			(at 0 0 180)
			(layer "F.Fab")
			(effects
				(font
					(size 1.27 1.27)
				)
			)
		)
		(duplicate_pad_numbers_are_jumpers no)
		(fp_line
			(start 0.7874 0.4064)
			(end -0.7874 0.4064)
			(stroke
				(width 0.1524)
				(type default)
			)
			(layer "F.SilkS")
		)
		(fp_line
			(start 0.7874 -0.4064)
			(end 0.7874 0.4064)
			(stroke
				(width 0.1524)
				(type default)
			)
			(layer "F.SilkS")
		)
		(fp_line
			(start -0.7874 0.4064)
			(end -0.7874 -0.4064)
			(stroke
				(width 0.1524)
				(type default)
			)
			(layer "F.SilkS")
		)
		(fp_line
			(start -0.7874 -0.4064)
			(end 0.7874 -0.4064)
			(stroke
				(width 0.1524)
				(type default)
			)
			(layer "F.SilkS")
		)
		(fp_line
			(start 0.67945 0.3048)
			(end 0.120396 0.3048)
			(stroke
				(width 0.1)
				(type default)
			)
			(layer "F.Fab")
		)
		(fp_line
			(start 0.67945 -0.3048)
			(end 0.67945 0.3048)
			(stroke
				(width 0.1)
				(type default)
			)
			(layer "F.Fab")
		)
		(fp_line
			(start 0.12065 -0.2794)
			(end 0.12065 -0.3048)
			(stroke
				(width 0.1)
				(type default)
			)
			(layer "F.Fab")
		)
		(fp_line
			(start 0.12065 -0.3048)
			(end 0.67945 -0.3048)
			(stroke
				(width 0.1)
				(type default)
			)
			(layer "F.Fab")
		)
		(fp_line
			(start 0.120396 0.3048)
			(end 0.120396 0.2794)
			(stroke
				(width 0.1)
				(type default)
			)
			(layer "F.Fab")
		)
		(fp_line
			(start 0.120396 0.2794)
			(end -0.12065 0.2794)
			(stroke
				(width 0.1)
				(type default)
			)
			(layer "F.Fab")
		)
		(fp_line
			(start -0.12065 0.3048)
			(end -0.67945 0.3048)
			(stroke
				(width 0.1)
				(type default)
			)
			(layer "F.Fab")
		)
		(fp_line
			(start -0.12065 0.2794)
			(end -0.12065 0.3048)
			(stroke
				(width 0.1)
				(type default)
			)
			(layer "F.Fab")
		)
		(fp_line
			(start -0.12065 -0.2794)
			(end 0.12065 -0.2794)
			(stroke
				(width 0.1)
				(type default)
			)
			(layer "F.Fab")
		)
		(fp_line
			(start -0.12065 -0.305054)
			(end -0.12065 -0.2794)
			(stroke
				(width 0.1)
				(type default)
			)
			(layer "F.Fab")
		)
		(fp_line
			(start -0.67945 0.3048)
			(end -0.67945 -0.305054)
			(stroke
				(width 0.1)
				(type default)
			)
			(layer "F.Fab")
		)
		(fp_line
			(start -0.67945 -0.305054)
			(end -0.12065 -0.305054)
			(stroke
				(width 0.1)
				(type default)
			)
			(layer "F.Fab")
		)
		(pad "1" smd circle
			(at -0.40005 0 180)
			(size 0 0)
			(layers "F.Cu" "F.Mask" "F.Paste")
			(net "FM_SMB_CPU0_ALERT")
		)
		(pad "2" smd circle
			(at 0.40005 0 180)
			(size 0 0)
			(layers "F.Cu" "F.Mask" "F.Paste")
			(net "FM_SMB_PEHPCPU0_PCIE_ALERT_N")
		)
	)
)
